# BASEBOARD_FAB2 (Tioga Pass) — schematic netlist excerpt (pin names and nets, part order shuffled) for the footprints in the layout excerpt that follows; sources: Cadence DE-HDL packaged netlist, KiCad conversion of Wiwynn_Tioga_Pass_MB.brd

C2A15  CAP_A  47UF 4V 20% X5R  pkg 0603V  page 228 : A = PVDDQ_KLM ; B = GND
CR1F4  DIODE  SDMK0340L IC  pkg SM  page 181 : C = FM_MATED_IN_D1_N ; A = FM_MATED_IN_N
C1G25  CAP_A  0.1UF 16V 10% X7R  pkg 0402V  page 223 : A = VR_PVDDQ_GHJ_VDD ; B = GND

(kicad_pcb
	(version 20260206)
	(generator "pcbnew")
	(generator_version "10.0")
	(general
		(thickness 1.6)
		(legacy_teardrops no)
	)
	(paper "A4")
	(title_block
		(title "Wiwynn_Tioga_Pass_MB.brd")
		(comment 1 "Tioga Pass / footprints 2239-2241 of 4770")
	)
	(layers
		(0 "F.Cu" signal "TOP")
		(4 "In1.Cu" signal "L2GND")
		(6 "In2.Cu" signal "L3")
		(8 "In3.Cu" signal "L4GND")
		(10 "In4.Cu" signal "L5")
		(12 "In5.Cu" signal "L6GND")
		(14 "In6.Cu" signal "L7VCC")
		(16 "In7.Cu" signal "L8VCC")
		(18 "In8.Cu" signal "L9GND")
		(20 "In9.Cu" signal "L10")
		(22 "In10.Cu" signal "L11GND")
		(24 "In11.Cu" signal "L12")
		(26 "In12.Cu" signal "L13GND")
		(2 "B.Cu" signal "BOTTOM")
		(9 "F.Adhes" user "F.Adhesive")
		(11 "B.Adhes" user "B.Adhesive")
		(13 "F.Paste" user "Package Geometry/Pastemask Top")
		(15 "B.Paste" user "Package Geometry/Pastemask Bottom")
		(5 "F.SilkS" user "Ref Des/Silkscreen Top")
		(7 "B.SilkS" user "Ref Des/Silkscreen Bottom")
		(1 "F.Mask" user "Board Geometry/Soldermask Top")
		(3 "B.Mask" user "Board Geometry/Soldermask Bottom")
		(17 "Dwgs.User" user "User.Drawings")
		(19 "Cmts.User" user "User.Comments")
		(21 "Eco1.User" user "User.Eco1")
		(23 "Eco2.User" user "User.Eco2")
		(25 "Edge.Cuts" user "Board Geometry/Outline")
		(27 "Margin" user)
		(31 "F.CrtYd" user "Package Geometry/Place Bound Top")
		(29 "B.CrtYd" user "Package Geometry/Place Bound Bottom")
		(35 "F.Fab" user "Ref Des/Assembly Top")
		(33 "B.Fab" user "Ref Des/Assembly Bottom")
	)
	(footprint ""
		(layer "F.Cu")
		(at 22.479 -32.258)
		(property "Reference" "CR1F4"
			(at -1.016 -1.24333 0)
			(unlocked yes)
			(layer "F.SilkS")
			(effects
				(font
					(size 0.7874 0.5842)
					(thickness 0.1524)
				)
				(justify left)
			)
		)
		(property "Value" ""
			(at 0 0 0)
			(layer "F.Fab")
			(effects
				(font
					(size 1.27 1.27)
				)
			)
		)
		(duplicate_pad_numbers_are_jumpers no)
		(fp_line
			(start -1.8161 1.664462)
			(end -1.335278 0.831596)
			(stroke
				(width 0.1524)
				(type default)
			)
			(layer "F.SilkS")
		)
		(fp_line
			(start -1.335278 -0.291846)
			(end -1.335278 0.831596)
			(stroke
				(width 0.1524)
				(type default)
			)
			(layer "F.SilkS")
		)
		(fp_line
			(start -1.335278 0.831596)
			(end -0.854456 1.664462)
			(stroke
				(width 0.1524)
				(type default)
			)
			(layer "F.SilkS")
		)
		(fp_line
			(start -1.335278 1.664462)
			(end -1.8161 1.664462)
			(stroke
				(width 0.1524)
				(type default)
			)
			(layer "F.SilkS")
		)
		(fp_line
			(start -1.335278 2.576068)
			(end -1.335278 1.664462)
			(stroke
				(width 0.1524)
				(type default)
			)
			(layer "F.SilkS")
		)
		(fp_line
			(start -0.854456 0.831596)
			(end -1.8161 0.831596)
			(stroke
				(width 0.1524)
				(type default)
			)
			(layer "F.SilkS")
		)
		(fp_line
			(start -0.854456 1.664462)
			(end -1.335278 1.664462)
			(stroke
				(width 0.1524)
				(type default)
			)
			(layer "F.SilkS")
		)
		(fp_rect
			(start -0.67437 2.04216)
			(end 0.67437 0.24384)
			(stroke
				(width 0)
				(type default)
			)
			(fill no)
			(layer "F.CrtYd")
		)
		(fp_line
			(start -1.8161 1.664462)
			(end -1.335278 0.831596)
			(stroke
				(width 0.1)
				(type default)
			)
			(layer "F.Fab")
		)
		(fp_line
			(start -1.335278 0.831596)
			(end -1.335278 -0.291846)
			(stroke
				(width 0.1)
				(type default)
			)
			(layer "F.Fab")
		)
		(fp_line
			(start -1.335278 0.831596)
			(end -0.854456 1.664462)
			(stroke
				(width 0.1)
				(type default)
			)
			(layer "F.Fab")
		)
		(fp_line
			(start -1.335278 1.664462)
			(end -1.335278 2.576068)
			(stroke
				(width 0.1)
				(type default)
			)
			(layer "F.Fab")
		)
		(fp_line
			(start -0.854456 0.831596)
			(end -1.8161 0.831596)
			(stroke
				(width 0.1)
				(type default)
			)
			(layer "F.Fab")
		)
		(fp_line
			(start -0.854456 1.664462)
			(end -1.8161 1.664462)
			(stroke
				(width 0.1)
				(type default)
			)
			(layer "F.Fab")
		)
		(fp_line
			(start -0.67437 0.24384)
			(end -0.67437 2.04216)
			(stroke
				(width 0.1)
				(type default)
			)
			(layer "F.Fab")
		)
		(fp_line
			(start -0.67437 2.04216)
			(end 0.67437 2.04216)
			(stroke
				(width 0.1)
				(type default)
			)
			(layer "F.Fab")
		)
		(fp_line
			(start 0.67437 0.24384)
			(end -0.67437 0.24384)
			(stroke
				(width 0.1)
				(type default)
			)
			(layer "F.Fab")
		)
		(fp_line
			(start 0.67437 2.04216)
			(end 0.67437 0.24384)
			(stroke
				(width 0.1)
				(type default)
			)
			(layer "F.Fab")
		)
		(pad "1" smd rect
			(at 0 0)
			(size 0.4064 1.016)
			(layers "F.Cu" "F.Mask" "F.Paste")
			(net "FM_MATED_IN_D1_N")
		)
		(pad "2" smd rect
			(at 0 2.286)
			(size 0.4064 1.016)
			(layers "F.Cu" "F.Mask" "F.Paste")
			(net "FM_MATED_IN_N")
		)
	)
	(footprint ""
		(layer "F.Cu")
		(at 104.5591 -140.208 90)
		(property "Reference" "C2A15"
			(at 1.848866 0.752348 90)
			(unlocked yes)
			(layer "F.SilkS")
			(effects
				(font
					(size 1.27 0.9652)
					(thickness 0.1524)
				)
			)
		)
		(property "Value" ""
			(at 0 0 90)
			(layer "F.Fab")
			(effects
				(font
					(size 1.27 1.27)
				)
			)
		)
		(duplicate_pad_numbers_are_jumpers no)
		(fp_rect
			(start -0.500126 1.598422)
			(end 0.500126 -0.201422)
			(stroke
				(width 0)
				(type default)
			)
			(fill no)
			(layer "F.CrtYd")
		)
		(fp_line
			(start 0.500126 -0.201422)
			(end 0.500126 1.598422)
			(stroke
				(width 0.1)
				(type default)
			)
			(layer "F.Fab")
		)
		(fp_line
			(start -0.500126 -0.201422)
			(end 0.500126 -0.201422)
			(stroke
				(width 0.1)
				(type default)
			)
			(layer "F.Fab")
		)
		(fp_line
			(start 0.500126 1.598422)
			(end -0.500126 1.598422)
			(stroke
				(width 0.1)
				(type default)
			)
			(layer "F.Fab")
		)
		(fp_line
			(start -0.500126 1.598422)
			(end -0.500126 -0.201422)
			(stroke
				(width 0.1)
				(type default)
			)
			(layer "F.Fab")
		)
		(pad "1" smd rect
			(at 0 0)
			(size 0.889 0.9906)
			(layers "F.Cu" "F.Mask" "F.Paste")
			(net "PVDDQ_KLM")
		)
		(pad "2" smd rect
			(at 0 1.397)
			(size 0.889 0.9906)
			(layers "F.Cu" "F.Mask" "F.Paste")
			(net "GND")
		)
		(zone
			(layer "F.Cu")
			(hatch none 0.5)
			(connect_pads
				(clearance 0)
			)
			(min_thickness 0.25)
			(keepout
				(tracks not_allowed)
				(vias allowed)
				(pads allowed)
				(copperpour not_allowed)
				(footprints allowed)
			)
			(placement
				(enabled no)
				(sheetname "")
			)
			(fill
				(thermal_gap 0.5)
				(thermal_bridge_width 0.5)
				(island_removal_mode 0)
			)
			(polygon
				(pts
					(xy 105.5116 -139.7127) (xy 105.5116 -140.7033) (xy 105.0036 -140.7033) (xy 105.0036 -139.7127)
				)
			)
		)
		(zone
			(layer "F.Cu")
			(hatch none 0.5)
			(connect_pads
				(clearance 0)
			)
			(min_thickness 0.25)
			(keepout
				(tracks allowed)
				(vias not_allowed)
				(pads allowed)
				(copperpour not_allowed)
				(footprints allowed)
			)
			(placement
				(enabled no)
				(sheetname "")
			)
			(fill
				(thermal_gap 0.5)
				(thermal_bridge_width 0.5)
				(island_removal_mode 0)
			)
			(polygon
				(pts
					(xy 105.5116 -139.7127) (xy 105.5116 -140.7033) (xy 105.0036 -140.7033) (xy 105.0036 -139.7127)
				)
			)
		)
	)
	(footprint ""
		(layer "F.Cu")
		(at 13.54836 4.266184)
		(property "Reference" "C1G25"
			(at 0 0 0)
			(layer "F.SilkS")
			(hide yes)
			(effects
				(font
					(size 1.27 1.27)
				)
			)
		)
		(property "Value" ""
			(at 0 0 0)
			(layer "F.Fab")
			(effects
				(font
					(size 1.27 1.27)
				)
			)
		)
		(duplicate_pad_numbers_are_jumpers no)
		(fp_rect
			(start 0.3048 -0.1016)
			(end -0.3048 0.9906)
			(stroke
				(width 0)
				(type default)
			)
			(fill no)
			(layer "F.CrtYd")
		)
		(fp_line
			(start -0.3048 -0.1016)
			(end -0.3048 0.9906)
			(stroke
				(width 0.1)
				(type default)
			)
			(layer "F.Fab")
		)
		(fp_line
			(start -0.3048 0.9906)
			(end 0.3048 0.9906)
			(stroke
				(width 0.1)
				(type default)
			)
			(layer "F.Fab")
		)
		(fp_line
			(start 0.3048 -0.1016)
			(end -0.3048 -0.1016)
			(stroke
				(width 0.1)
				(type default)
			)
			(layer "F.Fab")
		)
		(fp_line
			(start 0.3048 0.9906)
			(end 0.3048 -0.1016)
			(stroke
				(width 0.1)
				(type default)
			)
			(layer "F.Fab")
		)
		(pad "1" smd rect
			(at 0 0)
			(size 0.508 0.508)
			(layers "F.Cu" "F.Mask" "F.Paste")
			(net "VR_PVDDQ_GHJ_VDD")
		)
		(pad "2" smd rect
			(at 0 0.889)
			(size 0.508 0.508)
			(layers "F.Cu" "F.Mask" "F.Paste")
			(net "GND")
		)
		(zone
			(layer "F.Cu")
			(hatch none 0.5)
			(connect_pads
				(clearance 0)
			)
			(min_thickness 0.25)
			(keepout
				(tracks not_allowed)
				(vias allowed)
				(pads allowed)
				(copperpour not_allowed)
				(footprints allowed)
			)
			(placement
				(enabled no)
				(sheetname "")
			)
			(fill
				(thermal_gap 0.5)
				(thermal_bridge_width 0.5)
				(island_removal_mode 0)
			)
			(polygon
				(pts
					(xy 13.80236 4.520184) (xy 13.29436 4.520184) (xy 13.29436 4.901184) (xy 13.80236 4.901184)
				)
			)
		)
		(zone
			(layer "F.Cu")
			(hatch none 0.5)
			(connect_pads
				(clearance 0)
			)
			(min_thickness 0.25)
			(keepout
				(tracks allowed)
				(vias not_allowed)
				(pads allowed)
				(copperpour not_allowed)
				(footprints allowed)
			)
			(placement
				(enabled no)
				(sheetname "")
			)
			(fill
				(thermal_gap 0.5)
				(thermal_bridge_width 0.5)
				(island_removal_mode 0)
			)
			(polygon
				(pts
					(xy 13.80236 4.520184) (xy 13.29436 4.520184) (xy 13.29436 4.901184) (xy 13.80236 4.901184)
				)
			)
		)
	)
)
